(kicad_pcb
	(version 20221018)
	(generator pcbnew)
	(general
    (thickness 1.7403)
  )
	(paper "A4")
	(title_block
    (title "Data Center RDIMM DDR4 Tester")
    (date "2024-09-30")
    (rev "1.2.4")
		(comment 9 "footprints 607-615 of 690")
	)
	(layers
    (0 "F.Cu" signal)
    (1 "In1.Cu" power)
    (2 "In2.Cu" signal)
    (3 "In3.Cu" power)
    (4 "In4.Cu" power)
    (5 "In5.Cu" signal)
    (6 "In6.Cu" power)
    (7 "In7.Cu" signal)
    (8 "In8.Cu" power)
    (9 "In9.Cu" signal)
    (10 "In10.Cu" power)
    (31 "B.Cu" signal)
    (32 "B.Adhes" user "B.Adhesive")
    (33 "F.Adhes" user "F.Adhesive")
    (34 "B.Paste" user)
    (35 "F.Paste" user)
    (36 "B.SilkS" user "B.Silkscreen")
    (37 "F.SilkS" user "F.Silkscreen")
    (38 "B.Mask" user)
    (39 "F.Mask" user)
    (40 "Dwgs.User" user "User.Drawings")
    (41 "Cmts.User" user "User.Comments")
    (42 "Eco1.User" user "User.Eco1")
    (43 "Eco2.User" user "User.Eco2")
    (44 "Edge.Cuts" user)
    (45 "Margin" user)
    (46 "B.CrtYd" user "B.Courtyard")
    (47 "F.CrtYd" user "F.Courtyard")
    (48 "B.Fab" user)
    (49 "F.Fab" user)
  )
	(footprint "data-center-rdimm-ddr4-tester-footprints:C_0402_1005Metric" (layer "B.Cu")
    (at 131.425 105.55 90)
    (descr "Capacitor SMD 0402")
    (tags "capacitor SMD 0402")
    (property "Author" "Antmicro")
    (property "Dielectric" "X5R")
    (property "License" "Apache-2.0")
    (property "MPN" "GRM155R61H104KE14D")
    (property "Manufacturer" "Murata")
    (property "Sheetfile" "supply.kicad_sch")
    (property "Sheetname" "Supply")
    (property "Val" "100n")
    (property "Voltage" "50V")
    (property "ki_description" " ")
    (attr smd)
    (fp_text reference "C236" (at 0.88 1.205 270) (layer "B.SilkS")
        (effects (font (size 0.7 0.7) (thickness 0.15)) (justify left bottom mirror))
    )
    (fp_text value "C_100n_0402" (at 0 -1.4 270) (layer "B.Fab") hide
        (effects (font (size 0.7 0.7) (thickness 0.15)) (justify left bottom mirror))
    )
    (fp_text user "License: Apache-2.0" (at -0.932 -5.17 270) (layer "B.Fab") hide
        (effects (font (size 0.7 0.7) (thickness 0.15)) (justify left bottom mirror))
    )
    (fp_text user "${REFERENCE}" (at -0.932 -3.168 270) (layer "B.Fab") hide
        (effects (font (size 0.7 0.7) (thickness 0.15)) (justify left bottom mirror))
    )
    (fp_text user "Author: Antmicro" (at -0.932 -4.17 270) (layer "B.Fab") hide
        (effects (font (size 0.7 0.7) (thickness 0.15)) (justify left bottom mirror))
    )
    (fp_rect (start -0.94 0.47) (end 0.94 -0.47)
      (stroke (width 0.05) (type solid)) (fill none) (layer "B.CrtYd"))
    (fp_rect (start -0.499 0.249) (end 0.499 -0.249)
      (stroke (width 0.15) (type solid)) (fill none) (layer "B.Fab"))
    (pad "1" smd roundrect (at -0.484 0 90) (size 0.59 0.64) (layers "B.Cu" "B.Paste" "B.Mask") (roundrect_rratio 0.25)
      (net 307 "5V0_SYS") (pintype "passive"))
    (pad "2" smd roundrect (at 0.484 0 90) (size 0.59 0.64) (layers "B.Cu" "B.Paste" "B.Mask") (roundrect_rratio 0.25)
      (net 9 "GND") (pintype "passive"))
  )
	(footprint "data-center-rdimm-ddr4-tester-footprints:R_0402_1005Metric" (layer "B.Cu")
    (at 176.25 127.105 180)
    (descr "Resistor SMD 0402")
    (tags "resistor SMD 0402")
    (property "Author" "Antmicro")
    (property "DNP" "DNP")
    (property "License" "Apache-2.0")
    (property "MPN" "CR0402-FX-1002GLF")
    (property "Manufacturer" "Bourns")
    (property "Sheetfile" "ethernet.kicad_sch")
    (property "Sheetname" "Ethernet")
    (property "Tolerance" "1%")
    (property "Val" "10k")
    (property "dnp" "")
    (property "exclude_from_bom" "")
    (property "ki_description" "10k resistor in 0402 package with 1% tolerance")
    (attr exclude_from_pos_files exclude_from_bom)
    (fp_text reference "R182" (at 0.73 -0.445) (layer "B.SilkS")
        (effects (font (size 0.7 0.7) (thickness 0.15)) (justify left bottom mirror))
    )
    (fp_text value "R_10k_0402" (at 0 -1.4) (layer "B.Fab") hide
        (effects (font (size 0.7 0.7) (thickness 0.15)) (justify left bottom mirror))
    )
    (fp_text user "License: Apache-2.0" (at -0.95 -5.169) (layer "B.Fab") hide
        (effects (font (size 0.7 0.7) (thickness 0.15)) (justify left bottom mirror))
    )
    (fp_text user "Author: Antmicro" (at -0.95 -4.169) (layer "B.Fab") hide
        (effects (font (size 0.7 0.7) (thickness 0.15)) (justify left bottom mirror))
    )
    (fp_text user "${REFERENCE}" (at -0.95 -3.168) (layer "B.Fab") hide
        (effects (font (size 0.7 0.7) (thickness 0.15)) (justify left bottom mirror))
    )
    (fp_rect (start -0.93 0.47) (end 0.93 -0.47)
      (stroke (width 0.05) (type solid)) (fill none) (layer "B.CrtYd"))
    (fp_rect (start -0.5 0.25) (end 0.5 -0.25)
      (stroke (width 0.15) (type solid)) (fill none) (layer "B.Fab"))
    (pad "1" smd roundrect (at -0.485 0 180) (size 0.59 0.64) (layers "B.Cu" "B.Paste" "B.Mask") (roundrect_rratio 0.25)
      (net 659 "Net-(U13-~{BT})") (pintype "passive"))
    (pad "2" smd roundrect (at 0.485 0 180) (size 0.59 0.64) (layers "B.Cu" "B.Paste" "B.Mask") (roundrect_rratio 0.25)
      (net 360 "/Ethernet/VDD") (pintype "passive"))
  )
	(footprint "data-center-rdimm-ddr4-tester-footprints:C_0201" (layer "B.Cu")
    (at 189.8 80 90)
    (descr "Capacitor SMD 0201")
    (tags "capacitor SMD 0201")
    (property "Author" "Antmicro")
    (property "Dielectric" "")
    (property "License" "Apache-2.0")
    (property "MPN" "CC0201KRX6S5BB104")
    (property "Manufacturer" "Yaego")
    (property "Sheetfile" "fpga-power.kicad_sch")
    (property "Sheetname" "FPGA power")
    (property "Val" "100n")
    (property "Voltage" "")
    (property "ki_description" " ")
    (attr smd)
    (fp_text reference "C286" (at 1.13 1.19 270) (layer "B.SilkS")
        (effects (font (size 0.7 0.7) (thickness 0.15)) (justify left bottom mirror))
    )
    (fp_text value "C_100n_0201" (at 0 -1.4 270) (layer "B.Fab") hide
        (effects (font (size 0.7 0.7) (thickness 0.15)) (justify left bottom mirror))
    )
    (fp_text user "Author: Antmicro" (at -0.72 -5.4 270) (layer "B.Fab") hide
        (effects (font (size 0.7 0.7) (thickness 0.15)) (justify left bottom mirror))
    )
    (fp_text user "${REFERENCE}" (at -0.72 -3.4 270) (layer "B.Fab") hide
        (effects (font (size 0.7 0.7) (thickness 0.15)) (justify left bottom mirror))
    )
    (fp_text user "License: Apache-2.0" (at -0.72 -4.4 270) (layer "B.Fab") hide
        (effects (font (size 0.7 0.7) (thickness 0.15)) (justify left bottom mirror))
    )
    (fp_rect (start -0.72 0.38) (end 0.72 -0.38)
      (stroke (width 0.05) (type solid)) (fill none) (layer "B.CrtYd"))
    (fp_rect (start 0.3 -0.15) (end -0.301 0.149)
      (stroke (width 0.15) (type solid)) (fill none) (layer "B.Fab"))
    (pad "" smd roundrect (at -0.349 0.002 90) (size 0.318 0.36) (layers "B.Paste") (roundrect_rratio 0.25))
    (pad "" smd roundrect (at 0.341 0.002 90) (size 0.318 0.36) (layers "B.Paste") (roundrect_rratio 0.25))
    (pad "1" smd roundrect (at -0.321 0.002 90) (size 0.46 0.4) (layers "B.Cu" "B.Mask") (roundrect_rratio 0.25)
      (net 77 "VDDQ") (pintype "passive"))
    (pad "2" smd roundrect (at 0.32 0.002 90) (size 0.46 0.4) (layers "B.Cu" "B.Mask") (roundrect_rratio 0.25)
      (net 9 "GND") (pintype "passive"))
  )
	(footprint "data-center-rdimm-ddr4-tester-footprints:R_0402_1005Metric" (layer "B.Cu")
    (at 128.775 102.8)
    (descr "Resistor SMD 0402")
    (tags "resistor SMD 0402")
    (property "Author" "Antmicro")
    (property "Current" "1A")
    (property "DNP" "DNP")
    (property "License" "Apache-2.0")
    (property "MPN" "ERJ2GE0R00X")
    (property "Manufacturer" "Panasonic")
    (property "Sheetfile" "supply.kicad_sch")
    (property "Sheetname" "Supply")
    (property "Tolerance" "")
    (property "Val" "0R")
    (property "dnp" "")
    (property "exclude_from_bom" "")
    (property "ki_description" "0R resistor in 0402 package with unspecified tolerance")
    (attr exclude_from_pos_files exclude_from_bom)
    (fp_text reference "R191" (at 1.435 -0.53 180) (layer "B.SilkS")
        (effects (font (size 0.7 0.7) (thickness 0.15)) (justify left bottom mirror))
    )
    (fp_text value "R_0R_0402" (at 0 -1.4 180) (layer "B.Fab") hide
        (effects (font (size 0.7 0.7) (thickness 0.15)) (justify left bottom mirror))
    )
    (fp_text user "${REFERENCE}" (at -0.95 -3.168 180) (layer "B.Fab") hide
        (effects (font (size 0.7 0.7) (thickness 0.15)) (justify left bottom mirror))
    )
    (fp_text user "License: Apache-2.0" (at -0.95 -5.169 180) (layer "B.Fab") hide
        (effects (font (size 0.7 0.7) (thickness 0.15)) (justify left bottom mirror))
    )
    (fp_text user "Author: Antmicro" (at -0.95 -4.169 180) (layer "B.Fab") hide
        (effects (font (size 0.7 0.7) (thickness 0.15)) (justify left bottom mirror))
    )
    (fp_rect (start -0.93 0.47) (end 0.93 -0.47)
      (stroke (width 0.05) (type solid)) (fill none) (layer "B.CrtYd"))
    (fp_rect (start -0.5 0.25) (end 0.5 -0.25)
      (stroke (width 0.15) (type solid)) (fill none) (layer "B.Fab"))
    (pad "1" smd roundrect (at -0.485 0) (size 0.59 0.64) (layers "B.Cu" "B.Paste" "B.Mask") (roundrect_rratio 0.25)
      (net 536 "/Supply/SYS_PWR_GOOD") (pintype "passive"))
    (pad "2" smd roundrect (at 0.485 0) (size 0.59 0.64) (layers "B.Cu" "B.Paste" "B.Mask") (roundrect_rratio 0.25)
      (net 790 "/Supply/PWR_SEQ_EN") (pintype "passive"))
  )
	(footprint "data-center-rdimm-ddr4-tester-footprints:Fiducial_1mm_Mask2mm" (layer "B.Cu")
    (at 252.65 133.95 180)
    (descr "Circular Fiducial, 1mm bare copper, 3mm soldermask opening")
    (tags "fiducial")
    (property "Author" "Antmicro")
    (property "License" "Apache-2.0")
    (property "MPN" "")
    (property "Manufacturer" "")
    (property "Sheetfile" "data-center-rdimm-ddr4-tester.kicad_sch")
    (property "Sheetname" "")
    (property "exclude_from_bom" "")
    (property "ki_description" "Fiducial Marker for use with single board only")
    (attr exclude_from_pos_files exclude_from_bom)
    (fp_text reference "FID4" (at -2.2 1.38) (layer "B.SilkS")
        (effects (font (size 0.7 0.7) (thickness 0.15)) (justify left bottom mirror))
    )
    (fp_text value "Fiducial_1mm_Mask2mm" (at 0 -2.2) (layer "B.Fab")
        (effects (font (size 0.7 0.7) (thickness 0.15)) (justify left bottom mirror))
    )
    (fp_text user "Author: Antmicro" (at -1.25 -5.803) (layer "B.Fab") hide
        (effects (font (size 0.7 0.7) (thickness 0.15)) (justify left bottom mirror))
    )
    (fp_text user "${REFERENCE}" (at -1.25 -4.603) (layer "B.Fab") hide
        (effects (font (size 0.7 0.7) (thickness 0.15)) (justify left bottom mirror))
    )
    (fp_text user "License: Apache-2.0" (at -1.25 -7.003) (layer "B.Fab") hide
        (effects (font (size 0.7 0.7) (thickness 0.15)) (justify left bottom mirror))
    )
    (fp_circle (center 0 0) (end 1.24 0)
      (stroke (width 0.05) (type solid)) (fill none) (layer "B.CrtYd"))
    (fp_circle (center 0 0) (end 0.999 0)
      (stroke (width 0.15) (type solid)) (fill none) (layer "B.Fab"))
    (pad "" smd circle (at 0 0 180) (size 1 1) (layers "B.Cu" "B.Mask")
      (solder_mask_margin 0.5) (clearance 0.5))
  )
	(footprint "data-center-rdimm-ddr4-tester-footprints:R_0402_1005Metric" (layer "B.Cu")
    (at 166.2 101.8 180)
    (descr "Resistor SMD 0402")
    (tags "resistor SMD 0402")
    (property "Author" "Antmicro")
    (property "Current" "1A")
    (property "DNP" "DNP")
    (property "License" "Apache-2.0")
    (property "MPN" "ERJ2GE0R00X")
    (property "Manufacturer" "Panasonic")
    (property "Sheetfile" "ethernet.kicad_sch")
    (property "Sheetname" "Ethernet")
    (property "Tolerance" "")
    (property "Val" "0R")
    (property "dnp" "")
    (property "exclude_from_bom" "")
    (property "ki_description" "0R resistor in 0402 package with unspecified tolerance")
    (attr exclude_from_pos_files exclude_from_bom)
    (fp_text reference "R206" (at -1.91 -2.27) (layer "B.SilkS")
        (effects (font (size 0.7 0.7) (thickness 0.15)) (justify left bottom mirror))
    )
    (fp_text value "R_0R_0402" (at 0 -1.4) (layer "B.Fab") hide
        (effects (font (size 0.7 0.7) (thickness 0.15)) (justify left bottom mirror))
    )
    (fp_text user "License: Apache-2.0" (at -0.95 -5.169) (layer "B.Fab") hide
        (effects (font (size 0.7 0.7) (thickness 0.15)) (justify left bottom mirror))
    )
    (fp_text user "${REFERENCE}" (at -0.95 -3.168) (layer "B.Fab") hide
        (effects (font (size 0.7 0.7) (thickness 0.15)) (justify left bottom mirror))
    )
    (fp_text user "Author: Antmicro" (at -0.95 -4.169) (layer "B.Fab") hide
        (effects (font (size 0.7 0.7) (thickness 0.15)) (justify left bottom mirror))
    )
    (fp_rect (start -0.93 0.47) (end 0.93 -0.47)
      (stroke (width 0.05) (type solid)) (fill none) (layer "B.CrtYd"))
    (fp_rect (start -0.5 0.25) (end 0.5 -0.25)
      (stroke (width 0.15) (type solid)) (fill none) (layer "B.Fab"))
    (pad "1" smd roundrect (at -0.485 0 180) (size 0.59 0.64) (layers "B.Cu" "B.Paste" "B.Mask") (roundrect_rratio 0.25)
      (net 796 "ETH_SEL") (pintype "passive"))
    (pad "2" smd roundrect (at 0.485 0 180) (size 0.59 0.64) (layers "B.Cu" "B.Paste" "B.Mask") (roundrect_rratio 0.25)
      (net 662 "Net-(U16-SEL)") (pintype "passive"))
  )
	(footprint "data-center-rdimm-ddr4-tester-footprints:C_0402_1005Metric" (layer "B.Cu")
    (at 198.784 111.003)
    (descr "Capacitor SMD 0402")
    (tags "capacitor SMD 0402")
    (property "Author" "Antmicro")
    (property "Dielectric" "X5R")
    (property "License" "Apache-2.0")
    (property "MPN" "GRM155R61H104KE14D")
    (property "Manufacturer" "Murata")
    (property "Sheetfile" "ethernet.kicad_sch")
    (property "Sheetname" "Ethernet")
    (property "Val" "100n")
    (property "Voltage" "50V")
    (property "ki_description" " ")
    (attr smd)
    (fp_text reference "C229" (at 1.526 -0.643 180) (layer "B.SilkS")
        (effects (font (size 0.7 0.7) (thickness 0.15)) (justify left bottom mirror))
    )
    (fp_text value "C_100n_0402" (at 0 -1.4 180) (layer "B.Fab") hide
        (effects (font (size 0.7 0.7) (thickness 0.15)) (justify left bottom mirror))
    )
    (fp_text user "License: Apache-2.0" (at -0.932 -5.17 180) (layer "B.Fab") hide
        (effects (font (size 0.7 0.7) (thickness 0.15)) (justify left bottom mirror))
    )
    (fp_text user "Author: Antmicro" (at -0.932 -4.17 180) (layer "B.Fab") hide
        (effects (font (size 0.7 0.7) (thickness 0.15)) (justify left bottom mirror))
    )
    (fp_text user "${REFERENCE}" (at -0.932 -3.168 180) (layer "B.Fab") hide
        (effects (font (size 0.7 0.7) (thickness 0.15)) (justify left bottom mirror))
    )
    (fp_rect (start -0.94 0.47) (end 0.94 -0.47)
      (stroke (width 0.05) (type solid)) (fill none) (layer "B.CrtYd"))
    (fp_rect (start -0.499 0.249) (end 0.499 -0.249)
      (stroke (width 0.15) (type solid)) (fill none) (layer "B.Fab"))
    (pad "1" smd roundrect (at -0.484 0) (size 0.59 0.64) (layers "B.Cu" "B.Paste" "B.Mask") (roundrect_rratio 0.25)
      (net 864 "VIN_POE") (pintype "passive"))
    (pad "2" smd roundrect (at 0.484 0) (size 0.59 0.64) (layers "B.Cu" "B.Paste" "B.Mask") (roundrect_rratio 0.25)
      (net 9 "GND") (pintype "passive"))
  )
	(footprint "data-center-rdimm-ddr4-tester-footprints:SC70-3" (layer "B.Cu")
    (at 134.6 109.3 180)
    (property "Author" "Antmicro")
    (property "License" "Apache-2.0")
    (property "MPN" "BSS138PW")
    (property "Manufacturer" "Nexperia")
    (property "Sheetfile" "supply.kicad_sch")
    (property "Sheetname" "Supply")
    (property "ki_description" "60 V, 320 mA N-channel enhancement mode Trench MOSFET, SC-70-3 aka SOT-323 package")
    (property "ki_keywords" "n-channel enhancement mosfet sc70 sc-70 sot-323 sot323")
    (attr smd)
    (fp_text reference "Q11" (at -0.7 -1.19 90) (layer "B.SilkS")
        (effects (font (size 0.7 0.7) (thickness 0.15)) (justify left bottom mirror))
    )
    (fp_text value "BSS138PW" (at 0 -2.3) (layer "B.Fab") hide
        (effects (font (size 0.7 0.7) (thickness 0.15)) (justify left bottom mirror))
    )
    (fp_text user "Author: Antmicro" (at -1.45 -5.782) (layer "B.Fab") hide
        (effects (font (size 0.7 0.7) (thickness 0.15)) (justify left bottom mirror))
    )
    (fp_text user "License: Apache-2.0" (at -1.45 -6.782) (layer "B.Fab") hide
        (effects (font (size 0.7 0.7) (thickness 0.15)) (justify left bottom mirror))
    )
    (fp_text user "${REFERENCE}" (at -1.45 -4.783) (layer "B.Fab") hide
        (effects (font (size 0.7 0.7) (thickness 0.15)) (justify left bottom mirror))
    )
    (fp_line (start -0.3 -1) (end 0.627 -1.001)
      (stroke (width 0.15) (type solid)) (layer "B.SilkS"))
    (fp_line (start -0.3 1) (end 0.627 0.999)
      (stroke (width 0.15) (type solid)) (layer "B.SilkS"))
    (fp_line (start 0.627 -0.6) (end 0.627 -1.001)
      (stroke (width 0.15) (type solid)) (layer "B.SilkS"))
    (fp_line (start 0.627 0.6) (end 0.627 0.999)
      (stroke (width 0.15) (type solid)) (layer "B.SilkS"))
    (fp_rect (start 1.4 -1.3) (end -1.4 1.3)
      (stroke (width 0.05) (type solid)) (fill none) (layer "B.CrtYd"))
    (fp_rect (start -0.623 0.999) (end 0.627 -1.001)
      (stroke (width 0.15) (type solid)) (fill none) (layer "B.Fab"))
    (pad "1" smd rect (at -0.95 0.65 90) (size 0.6 0.8) (layers "B.Cu" "B.Paste" "B.Mask")
      (net 804 "FPGA_POWER_CYCLE") (pinfunction "G") (pintype "bidirectional"))
    (pad "2" smd rect (at -0.95 -0.65 90) (size 0.6 0.8) (layers "B.Cu" "B.Paste" "B.Mask")
      (net 9 "GND") (pinfunction "S") (pintype "bidirectional"))
    (pad "3" smd rect (at 0.95 0 90) (size 0.6 0.8) (layers "B.Cu" "B.Paste" "B.Mask")
      (net 583 "Net-(Q11-D)") (pinfunction "D") (pintype "bidirectional"))
  )
	(footprint "data-center-rdimm-ddr4-tester-footprints:R_0402_1005Metric" (layer "B.Cu")
    (at 228.55 123)
    (descr "Resistor SMD 0402")
    (tags "resistor SMD 0402")
    (property "Author" "Antmicro")
    (property "License" "Apache-2.0")
    (property "MPN" "CR0402-FX-1002GLF")
    (property "Manufacturer" "Bourns")
    (property "Sheetfile" "supply.kicad_sch")
    (property "Sheetname" "Supply")
    (property "Tolerance" "1%")
    (property "Val" "10k")
    (property "ki_description" "10k resistor in 0402 package with 1% tolerance")
    (attr smd)
    (fp_text reference "R220" (at 1.5 -1.52 180) (layer "B.SilkS")
        (effects (font (size 0.7 0.7) (thickness 0.15)) (justify left bottom mirror))
    )
    (fp_text value "R_10k_0402" (at 0 -1.4 180) (layer "B.Fab") hide
        (effects (font (size 0.7 0.7) (thickness 0.15)) (justify left bottom mirror))
    )
    (fp_text user "License: Apache-2.0" (at -0.95 -5.169 180) (layer "B.Fab") hide
        (effects (font (size 0.7 0.7) (thickness 0.15)) (justify left bottom mirror))
    )
    (fp_text user "${REFERENCE}" (at -0.95 -3.168 180) (layer "B.Fab") hide
        (effects (font (size 0.7 0.7) (thickness 0.15)) (justify left bottom mirror))
    )
    (fp_text user "Author: Antmicro" (at -0.95 -4.169 180) (layer "B.Fab") hide
        (effects (font (size 0.7 0.7) (thickness 0.15)) (justify left bottom mirror))
    )
    (fp_rect (start -0.93 0.47) (end 0.93 -0.47)
      (stroke (width 0.05) (type solid)) (fill none) (layer "B.CrtYd"))
    (fp_rect (start -0.5 0.25) (end 0.5 -0.25)
      (stroke (width 0.15) (type solid)) (fill none) (layer "B.Fab"))
    (pad "1" smd roundrect (at -0.485 0) (size 0.59 0.64) (layers "B.Cu" "B.Paste" "B.Mask") (roundrect_rratio 0.25)
      (net 860 "/Supply/~{CLR}") (pintype "passive"))
    (pad "2" smd roundrect (at 0.485 0) (size 0.59 0.64) (layers "B.Cu" "B.Paste" "B.Mask") (roundrect_rratio 0.25)
      (net 859 "/Supply/OUT") (pintype "passive"))
  )
)
